FILE_TYPE = MULTI_PHYS_TABLE;

PART 'DIODE_BIDIRECTIONAL'

{========================================================================================}
:VALUE         | PART_TYPE | MATERIAL | PART_NUMBER    = STANDARD    | LIFECYCLE     | PART_NUMBER   | JEDEC_TYPE    | DESCRIPTION                                | MANUFTR | MANUF_PN          | RD_CMPLS_LVL | CMPLS_LVL | CLASS | DIP_SMD | FP_ECN | FROM_PJ         | DATA                  | EE_CHECK_LIST | STATUS | PSL | PREFERENCE | CREATOR | CREATEDAY  | ESD_CDM | ESD_HBM | ESD_MM | MSD  | PIN_LENGTH_LONG_PIN | PIN_LENGTH_SHORT_PIN ;
{========================================================================================}
 'UCLAMP0511T' | 'SMLF'    | 'IC'     | 'BC00511TZ00'(!) = ''          | ''            | 'BC00511TZ00' |'SLP1006P2T'| 'DIODE SMD TVS UCLAMP0511T(5V,SLP1006P2T)' | 'STH'   | 'UCLAMP0511T.TCT' | 'EP(V1)'     | ''        | 'IC'  | ''      | ''     | 'JBR-CHIH-FENG' | 'STH_uClamp0511T.pdf' | ''            | ''     | ''  | ''         | ''      | '20130323' | ''      | ''      | ''     | ''   | ''                  | ''                  
 'UCLAMP0511T' | 'SMLF'    | 'EMPTY'  | 'BC00511TZ00'(!) = ''          | ''            | 'BC00511TZ00' |'SLP1006P2T'| 'DIODE SMD TVS UCLAMP0511T(5V,SLP1006P2T)' | 'STH'   | 'UCLAMP0511T.TCT' | 'EP(V1)'     | ''        | 'IC'  | ''      | ''     | 'JBR-CHIH-FENG' | 'STH_uClamp0511T.pdf' | ''            | ''     | ''  | ''         | ''      | '20130323' | ''      | ''      | ''     | ''   | ''                  | ''                  
 '5.0SMDJ14CA' | 'SMLF'    | 'IC'     | 'BC0MDJ14001'(!) = ''          | ''            | 'BC0MDJ14001' |'D2723_SMCXC'| 'DIODE SMD 5.0SMDJ14CA(14V,216A,5000W)'    | 'LFI'   | '5.0SMDJ14CA'     | 'EP(V1)'     | ''        | 'IC'  | ''      | ''     | 'F08-MARK'      | 'LFI_5.0SMDJ14CA.pdf' | ''            | ''     | ''  | ''         | ''      | '20160608' | ''      | ''      | ''     | ''   | ''                  | ''                  
 '5.0SMDJ14CA' | 'SMLF'    | 'EMPTY'  | 'BC0MDJ14001'(!) = ''          | ''            | 'BC0MDJ14001' |'D2723_SMCXC'| 'DIODE SMD 5.0SMDJ14CA(14V,216A,5000W)'    | 'LFI'   | '5.0SMDJ14CA'     | 'EP(V1)'     | ''        | 'IC'  | ''      | ''     | 'F08-MARK'      | 'LFI_5.0SMDJ14CA.pdf' | ''            | ''     | ''  | ''         | ''      | '20160608' | ''      | ''      | ''     | ''   | ''                  | ''                  
 '5.0SMDJ75CA' | 'SMLF'    | 'IC'     | 'BCDJ75CAZ00'(!) = ''          | ''            | 'BCDJ75CAZ00' |'D_SMDJ60A'| 'DIODE SMD 5.0SMDJ75CA(75V,41.4A,5000W)'   | 'LFI'   | '5.0SMDJ75CA'     | 'EP(V1)'     | ''        | 'IC'  | ''      | ''     | 'BAICELL-MJ'    | 'LFI_5.0SMDJ75CA.pdf' | ''            | ''     | ''  | ''         | ''      | '20190124' | 'NA'    | 'NA'    | 'NA'   | 'NA' | '0 MILS'            | '0 MILS'            
 '5.0SMDJ75CA' | 'SMLF'    | 'EMPTY'  | 'BCDJ75CAZ00'(!) = ''          | ''            | 'BCDJ75CAZ00' |'D_SMDJ60A'| 'DIODE SMD 5.0SMDJ75CA(75V,41.4A,5000W)'   | 'LFI'   | '5.0SMDJ75CA'     | 'EP(V1)'     | ''        | 'IC'  | ''      | ''     | 'BAICELL-MJ'    | 'LFI_5.0SMDJ75CA.pdf' | ''            | ''     | ''  | ''         | ''      | '20190124' | 'NA'    | 'NA'    | 'NA'   | 'NA' | '0 MILS'            | '0 MILS'            
 'SMCJ64CA'    | 'SMLF'    | 'IC'     | 'BCCJ64CAZ00'(!) = ''          | ''            | 'BCCJ64CAZ00' |'D2723_SMCXC'| 'DIODE SMD SMCJ64CA(64V,14.6A,1500W)'      | 'LFI'   | 'SMCJ64CA'        | 'EP(V1)'     | ''        | 'IC'  | ''      | ''     | 'BAICELL-MJ'    | 'LFI_SMCJ64CA.pdf'    | ''            | ''     | ''  | ''         | ''      | '20190130' | 'NA'    | 'NA'    | 'NA'   | 'NA' | '0 MILS'            | '0 MILS'            
 'SMCJ64CA'    | 'SMLF'    | 'EMPTY'  | 'BCCJ64CAZ00'(!) = ''          | ''            | 'BCCJ64CAZ00' |'D2723_SMCXC'| 'DIODE SMD SMCJ64CA(64V,14.6A,1500W)'      | 'LFI'   | 'SMCJ64CA'        | 'EP(V1)'     | ''        | 'IC'  | ''      | ''     | 'BAICELL-MJ'    | 'LFI_SMCJ64CA.pdf'    | ''            | ''     | ''  | ''         | ''      | '20190130' | 'NA'    | 'NA'    | 'NA'   | 'NA' | '0 MILS'            | '0 MILS'            
 '8.0SMDJ48CA' | 'SMLF'    | 'IC'     | 'BCDJ48CAZ00'(!) = ''               | ''               | 'BCDJ48CAZ00' |'D_SMDJ60A'| 'DIODE SMD 8.0SMDJ48CA(48V,103.4A,8000W)'  | 'LFI'   | '8.0SMDJ48CA'     | 'EP(V1)'     | ''        | 'IC'  | ''      | ''     | 'S3B-CLAIRE'    | 'LFI_8.0SMDJ48CA.pdf' | ''            | ''     | ''  | ''         | ''      | '20221114' | ''      | ''      | ''     | ''   | '0 MILS'            | '0 MILS'            
 '8.0SMDJ48CA' | 'SMLF'    | 'EMPTY'  | 'BCDJ48CAZ00'(!) = ''               | ''               | 'BCDJ48CAZ00' |'D_SMDJ60A'| 'DIODE SMD 8.0SMDJ48CA(48V,103.4A,8000W)'  | 'LFI'   | '8.0SMDJ48CA'     | 'EP(V1)'     | ''        | 'IC'  | ''      | ''     | 'S3B-CLAIRE'    | 'LFI_8.0SMDJ48CA.pdf' | ''            | ''     | ''  | ''         | ''      | '20221114' | ''      | ''      | ''     | ''   | '0 MILS'            | '0 MILS'            
 '8.0SMDJ75CA' | 'SMLF'    | 'IC'     | 'BCDJ75CAZ01'(!) = ''               | ''               | 'BCDJ75CAZ01' |'D_SMDJ60A'| 'DIODE SMD 8.0SMDJ75CA(75V,66.2A,8000W)'   | 'LFI'   | '8.0SMDJ75CA'     | 'EP(V1)'     | ''        | 'IC'  | ''      | ''     | 'S3B-CLAIRE'    | 'LFI_8.0SMDJ75CA.pdf' | ''            | ''     | ''  | ''         | ''      | '20221114' | ''      | ''      | ''     | ''   | '0 MILS'            | '0 MILS'            
 '8.0SMDJ75CA' | 'SMLF'    | 'EMPTY'  | 'BCDJ75CAZ01'(!) = ''               | ''               | 'BCDJ75CAZ01' |'D_SMDJ60A'| 'DIODE SMD 8.0SMDJ75CA(75V,66.2A,8000W)'   | 'LFI'   | '8.0SMDJ75CA'     | 'EP(V1)'     | ''        | 'IC'  | ''      | ''     | 'S3B-CLAIRE'    | 'LFI_8.0SMDJ75CA.pdf' | ''            | ''     | ''  | ''         | ''      | '20221114' | ''      | ''      | ''     | ''   | '0 MILS'            | '0 MILS'            

END_PART

END.

